(kicad_pcb
	(version 20241229)
	(generator "pcbnew")
	(generator_version "9.0")
	(general
		(thickness 1.711)
		(legacy_teardrops no)
	)
	(paper "A4")
	(title_block
		(title "Antmicro Baseboard for Jetson AGX Thor")
		(date "2026-02-18")
		(rev "1.1.0")
		(company "Antmicro Ltd")
		(comment 1 "www.antmicro.com")
		(comment 9 "footprints 725-729 of 1170")
	)
	(layers
		(0 "F.Cu" signal)
		(4 "In1.Cu" signal)
		(6 "In2.Cu" signal)
		(8 "In3.Cu" signal)
		(10 "In4.Cu" jumper)
		(12 "In5.Cu" signal)
		(14 "In6.Cu" signal)
		(16 "In7.Cu" signal)
		(18 "In8.Cu" signal)
		(2 "B.Cu" signal)
		(9 "F.Adhes" user "F.Adhesive")
		(11 "B.Adhes" user "B.Adhesive")
		(13 "F.Paste" user)
		(15 "B.Paste" user)
		(5 "F.SilkS" user "F.Silkscreen")
		(7 "B.SilkS" user "B.Silkscreen")
		(1 "F.Mask" user)
		(3 "B.Mask" user)
		(17 "Dwgs.User" user "User.Drawings")
		(19 "Cmts.User" user "User.Comments")
		(21 "Eco1.User" user "User.Eco1")
		(23 "Eco2.User" user "User.Eco2")
		(25 "Edge.Cuts" user)
		(27 "Margin" user)
		(31 "F.CrtYd" user "F.Courtyard")
		(29 "B.CrtYd" user "B.Courtyard")
		(35 "F.Fab" user)
		(33 "B.Fab" user)
	)
	(footprint "antmicro-footprints:C_0402_1005Metric"
		(layer "B.Cu")
		(at 180.285 78.175)
		(descr "Capacitor SMD 0402")
		(tags "capacitor SMD 0402")
		(property "Reference" "C266"
			(at -5.585 -0.375 0)
			(layer "B.SilkS")
			(effects
				(font
					(size 0.7 0.7)
					(thickness 0.15)
				)
				(justify right top mirror)
			)
		)
		(property "Value" "C_1u_25V_0402"
			(at -1.022927 -2.155213 0)
			(layer "B.Fab")
			(effects
				(font
					(size 0.7 0.7)
					(thickness 0.15)
				)
				(justify right top mirror)
			)
		)
		(property "Datasheet" "https://www.murata.com/products/productdetail?partno=GRM155R61E105KE11%23"
			(at 0 0 0)
			(layer "B.Fab")
			(hide yes)
			(effects
				(font
					(size 1.27 1.27)
					(thickness 0.15)
				)
				(justify mirror)
			)
		)
		(property "Description" "SMD Multilayer Ceramic Capacitor, 1 µF, 25 V, 0402 [1005 Metric], ± 10%, X5R, GRM Series"
			(at 0 0 0)
			(layer "B.Fab")
			(hide yes)
			(effects
				(font
					(size 1.27 1.27)
					(thickness 0.15)
				)
				(justify mirror)
			)
		)
		(property "MPN" "GRM155R61E105KE11J"
			(at 0 0 180)
			(unlocked yes)
			(layer "B.Fab")
			(hide yes)
			(effects
				(font
					(size 1 1)
					(thickness 0.15)
				)
				(justify mirror)
			)
		)
		(property "Manufacturer" "Murata"
			(at 0 0 180)
			(unlocked yes)
			(layer "B.Fab")
			(hide yes)
			(effects
				(font
					(size 1 1)
					(thickness 0.15)
				)
				(justify mirror)
			)
		)
		(property "License" "Apache-2.0"
			(at 0 0 180)
			(unlocked yes)
			(layer "B.Fab")
			(hide yes)
			(effects
				(font
					(size 1 1)
					(thickness 0.15)
				)
				(justify mirror)
			)
		)
		(property "Author" "Antmicro"
			(at 0 0 180)
			(unlocked yes)
			(layer "B.Fab")
			(hide yes)
			(effects
				(font
					(size 1 1)
					(thickness 0.15)
				)
				(justify mirror)
			)
		)
		(property "Val" "1u"
			(at 0 0 180)
			(unlocked yes)
			(layer "B.Fab")
			(hide yes)
			(effects
				(font
					(size 1 1)
					(thickness 0.15)
				)
				(justify mirror)
			)
		)
		(property "Voltage" "25V"
			(at 0 0 180)
			(unlocked yes)
			(layer "B.Fab")
			(hide yes)
			(effects
				(font
					(size 1 1)
					(thickness 0.15)
				)
				(justify mirror)
			)
		)
		(property "Dielectric" "X5R"
			(at 0 0 180)
			(unlocked yes)
			(layer "B.Fab")
			(hide yes)
			(effects
				(font
					(size 1 1)
					(thickness 0.15)
				)
				(justify mirror)
			)
		)
		(sheetname "/Power/")
		(sheetfile "power.kicad_sch")
		(attr smd)
		(fp_rect
			(start -0.925 0.47)
			(end 0.925 -0.47)
			(stroke
				(width 0.05)
				(type default)
			)
			(fill no)
			(layer "B.CrtYd")
		)
		(fp_line
			(start -0.494 -0.248)
			(end -0.494 0.25)
			(stroke
				(width 0.15)
				(type solid)
			)
			(layer "B.Fab")
		)
		(fp_line
			(start -0.494 0.25)
			(end 0.504 0.25)
			(stroke
				(width 0.15)
				(type solid)
			)
			(layer "B.Fab")
		)
		(fp_line
			(start 0.504 -0.248)
			(end -0.494 -0.248)
			(stroke
				(width 0.15)
				(type solid)
			)
			(layer "B.Fab")
		)
		(fp_line
			(start 0.504 0.25)
			(end 0.504 -0.248)
			(stroke
				(width 0.15)
				(type solid)
			)
			(layer "B.Fab")
		)
		(fp_text user "Author: Antmicro"
			(at -0.939 -3.399 0)
			(layer "B.Fab")
			(effects
				(font
					(size 0.7 0.7)
					(thickness 0.15)
				)
				(justify right top mirror)
			)
		)
		(fp_text user "${REFERENCE}"
			(at -0.939 -4.599 0)
			(layer "B.Fab")
			(effects
				(font
					(size 0.7 0.7)
					(thickness 0.15)
				)
				(justify right top mirror)
			)
		)
		(fp_text user "License: Apache-2.0"
			(at -0.939 -5.799 0)
			(layer "B.Fab")
			(effects
				(font
					(size 0.7 0.7)
					(thickness 0.15)
				)
				(justify right top mirror)
			)
		)
		(pad "1" smd roundrect
			(at -0.48 0)
			(size 0.59 0.64)
			(layers "B.Cu" "B.Mask" "B.Paste")
			(roundrect_rratio 0.25)
			(net 1 "GND")
			(pintype "passive")
		)
		(pad "2" smd roundrect
			(at 0.48 0)
			(size 0.59 0.64)
			(layers "B.Cu" "B.Mask" "B.Paste")
			(roundrect_rratio 0.25)
			(net 525 "/Power/USBPD2_HV")
			(pintype "passive")
		)
	)
	(footprint "antmicro-footprints:R_0402_1005Metric"
		(layer "B.Cu")
		(at 215.8 100.4 180)
		(descr "Resistor SMD 0402")
		(tags "resistor SMD 0402")
		(property "Reference" "R256"
			(at 1 -0.5 0)
			(layer "B.SilkS")
			(effects
				(font
					(size 0.7 0.7)
					(thickness 0.15)
				)
				(justify left bottom mirror)
			)
		)
		(property "Value" "R_10k_0402"
			(at -1.011843 -1.772047 0)
			(layer "B.Fab")
			(effects
				(font
					(size 0.7 0.7)
					(thickness 0.15)
				)
				(justify left bottom mirror)
			)
		)
		(property "Datasheet" "https://www.bourns.com/docs/product-datasheets/cr.pdf"
			(at 0 0 0)
			(layer "B.Fab")
			(hide yes)
			(effects
				(font
					(size 1.27 1.27)
					(thickness 0.15)
				)
				(justify mirror)
			)
		)
		(property "Description" "SMD Chip Resistor, 10 kohm, ± 1%, 62.5 mW, 0402 [1005 Metric], Thick Film, General Purpose"
			(at 0 0 0)
			(layer "B.Fab")
			(hide yes)
			(effects
				(font
					(size 1.27 1.27)
					(thickness 0.15)
				)
				(justify mirror)
			)
		)
		(property "Manufacturer" "Bourns"
			(at 0 0 0)
			(unlocked yes)
			(layer "B.Fab")
			(hide yes)
			(effects
				(font
					(size 1 1)
					(thickness 0.15)
				)
				(justify mirror)
			)
		)
		(property "MPN" "CR0402-FX-1002GLF"
			(at 0 0 0)
			(unlocked yes)
			(layer "B.Fab")
			(hide yes)
			(effects
				(font
					(size 1 1)
					(thickness 0.15)
				)
				(justify mirror)
			)
		)
		(property "Val" "10k"
			(at 0 0 0)
			(unlocked yes)
			(layer "B.Fab")
			(hide yes)
			(effects
				(font
					(size 1 1)
					(thickness 0.15)
				)
				(justify mirror)
			)
		)
		(property "License" "Apache-2.0"
			(at 0 0 0)
			(unlocked yes)
			(layer "B.Fab")
			(hide yes)
			(effects
				(font
					(size 1 1)
					(thickness 0.15)
				)
				(justify mirror)
			)
		)
		(property "Author" "Antmicro"
			(at 0 0 0)
			(unlocked yes)
			(layer "B.Fab")
			(hide yes)
			(effects
				(font
					(size 1 1)
					(thickness 0.15)
				)
				(justify mirror)
			)
		)
		(property "Tolerance" "1%"
			(at 0 0 0)
			(unlocked yes)
			(layer "B.Fab")
			(hide yes)
			(effects
				(font
					(size 1 1)
					(thickness 0.15)
				)
				(justify mirror)
			)
		)
		(sheetname "/Recovery USB/")
		(sheetfile "recovery_usb.kicad_sch")
		(attr smd)
		(fp_rect
			(start -0.925 0.47)
			(end 0.925 -0.47)
			(stroke
				(width 0.05)
				(type default)
			)
			(fill no)
			(layer "B.CrtYd")
		)
		(fp_rect
			(start -0.5 0.25)
			(end 0.5 -0.25)
			(stroke
				(width 0.15)
				(type solid)
			)
			(fill no)
			(layer "B.Fab")
		)
		(fp_text user "License: Apache-2.0"
			(at -0.95 -5.169 0)
			(layer "B.Fab")
			(effects
				(font
					(size 0.7 0.7)
					(thickness 0.15)
				)
				(justify left bottom mirror)
			)
		)
		(fp_text user "${REFERENCE}"
			(at -0.95 -3.168 0)
			(layer "B.Fab")
			(effects
				(font
					(size 0.7 0.7)
					(thickness 0.15)
				)
				(justify left bottom mirror)
			)
		)
		(fp_text user "Author: Antmicro"
			(at -0.95 -4.169 0)
			(layer "B.Fab")
			(effects
				(font
					(size 0.7 0.7)
					(thickness 0.15)
				)
				(justify left bottom mirror)
			)
		)
		(pad "1" smd roundrect
			(at -0.48 0 180)
			(size 0.59 0.64)
			(layers "B.Cu" "B.Mask" "B.Paste")
			(roundrect_rratio 0.25)
			(net 1014 "/Recovery USB/USBC2_FAULT_N")
			(pintype "passive")
		)
		(pad "2" smd roundrect
			(at 0.48 0 180)
			(size 0.59 0.64)
			(layers "B.Cu" "B.Mask" "B.Paste")
			(roundrect_rratio 0.25)
			(net 5 "+5V")
			(pintype "passive")
		)
	)
	(footprint "antmicro-footprints:R_0402_1005Metric"
		(layer "B.Cu")
		(at 196.68 77.16 180)
		(descr "Resistor SMD 0402")
		(tags "resistor SMD 0402")
		(property "Reference" "R106"
			(at -3.67 -0.44 0)
			(layer "B.SilkS")
			(effects
				(font
					(size 0.7 0.7)
					(thickness 0.15)
				)
				(justify left bottom mirror)
			)
		)
		(property "Value" "R_0R_0402"
			(at -1.011843 -1.772046 0)
			(layer "B.Fab")
			(effects
				(font
					(size 0.7 0.7)
					(thickness 0.15)
				)
				(justify left bottom mirror)
			)
		)
		(property "Datasheet" "https://industrial.panasonic.com/cdbs/www-data/pdf/RDA0000/AOA0000C301.pdf"
			(at 0 0 0)
			(layer "B.Fab")
			(hide yes)
			(effects
				(font
					(size 1.27 1.27)
					(thickness 0.15)
				)
				(justify mirror)
			)
		)
		(property "Description" "SMD Chip Resistor, Jumper, 0 ohm, 100 mW, 0402 [1005 Metric], Thick Film, General Purpose"
			(at 0 0 0)
			(layer "B.Fab")
			(hide yes)
			(effects
				(font
					(size 1.27 1.27)
					(thickness 0.15)
				)
				(justify mirror)
			)
		)
		(property "Manufacturer" "Panasonic"
			(at 0 0 0)
			(unlocked yes)
			(layer "B.Fab")
			(hide yes)
			(effects
				(font
					(size 1 1)
					(thickness 0.15)
				)
				(justify mirror)
			)
		)
		(property "MPN" "ERJ2GE0R00X"
			(at 0 0 0)
			(unlocked yes)
			(layer "B.Fab")
			(hide yes)
			(effects
				(font
					(size 1 1)
					(thickness 0.15)
				)
				(justify mirror)
			)
		)
		(property "Val" "0R"
			(at 0 0 0)
			(unlocked yes)
			(layer "B.Fab")
			(hide yes)
			(effects
				(font
					(size 1 1)
					(thickness 0.15)
				)
				(justify mirror)
			)
		)
		(property "License" "Apache-2.0"
			(at 0 0 0)
			(unlocked yes)
			(layer "B.Fab")
			(hide yes)
			(effects
				(font
					(size 1 1)
					(thickness 0.15)
				)
				(justify mirror)
			)
		)
		(property "Author" "Antmicro"
			(at 0 0 0)
			(unlocked yes)
			(layer "B.Fab")
			(hide yes)
			(effects
				(font
					(size 1 1)
					(thickness 0.15)
				)
				(justify mirror)
			)
		)
		(property "Tolerance" "~"
			(at 0 0 0)
			(unlocked yes)
			(layer "B.Fab")
			(hide yes)
			(effects
				(font
					(size 1 1)
					(thickness 0.15)
				)
				(justify mirror)
			)
		)
		(property "Current" "1A"
			(at 0 0 0)
			(unlocked yes)
			(layer "B.Fab")
			(hide yes)
			(effects
				(font
					(size 1 1)
					(thickness 0.15)
				)
				(justify mirror)
			)
		)
		(sheetname "/USB Debug, PD/")
		(sheetfile "usb_debug_pd.kicad_sch")
		(attr smd)
		(fp_poly
			(pts
				(xy -0.925 0.47) (xy 0.925 0.47) (xy 0.925 -0.47) (xy -0.925 -0.47)
			)
			(stroke
				(width 0.05)
				(type default)
			)
			(fill no)
			(layer "B.CrtYd")
		)
		(fp_poly
			(pts
				(xy -0.5 0.25) (xy 0.5 0.25) (xy 0.5 -0.25) (xy -0.5 -0.25)
			)
			(stroke
				(width 0.15)
				(type solid)
			)
			(fill no)
			(layer "B.Fab")
		)
		(fp_text user "License: Apache-2.0"
			(at -0.949999 -5.169 0)
			(layer "B.Fab")
			(effects
				(font
					(size 0.7 0.7)
					(thickness 0.15)
				)
				(justify left bottom mirror)
			)
		)
		(fp_text user "${REFERENCE}"
			(at -0.95 -3.168 0)
			(layer "B.Fab")
			(effects
				(font
					(size 0.7 0.7)
					(thickness 0.15)
				)
				(justify left bottom mirror)
			)
		)
		(fp_text user "Author: Antmicro"
			(at -0.95 -4.169 0)
			(layer "B.Fab")
			(effects
				(font
					(size 0.7 0.7)
					(thickness 0.15)
				)
				(justify left bottom mirror)
			)
		)
		(pad "1" smd roundrect
			(at -0.48 0 180)
			(size 0.59 0.64)
			(layers "B.Cu" "B.Mask" "B.Paste")
			(roundrect_rratio 0.25)
			(net 948 "/USB DP Alt mode/USBC_HPD")
			(pintype "passive")
		)
		(pad "2" smd roundrect
			(at 0.48 0 180)
			(size 0.59 0.64)
			(layers "B.Cu" "B.Mask" "B.Paste")
			(roundrect_rratio 0.25)
			(net 949 "/USB Debug, PD/PDC_HPD2")
			(pintype "passive")
		)
	)
	(footprint "antmicro-footprints:R_0402_1005Metric"
		(layer "B.Cu")
		(at 76 65.5 180)
		(descr "Resistor SMD 0402")
		(tags "resistor SMD 0402")
		(property "Reference" "R319"
			(at -1.6 -2.4 0)
			(layer "B.SilkS")
			(effects
				(font
					(size 0.7 0.7)
					(thickness 0.15)
				)
				(justify left bottom mirror)
			)
		)
		(property "Value" "R_10k_0402"
			(at -1.011843 -1.772046 0)
			(layer "B.Fab")
			(effects
				(font
					(size 0.7 0.7)
					(thickness 0.15)
				)
				(justify left bottom mirror)
			)
		)
		(property "Datasheet" "https://www.bourns.com/docs/product-datasheets/cr.pdf"
			(at 0 0 0)
			(layer "B.Fab")
			(hide yes)
			(effects
				(font
					(size 1.27 1.27)
					(thickness 0.15)
				)
				(justify mirror)
			)
		)
		(property "Description" "SMD Chip Resistor, 10 kohm, ± 1%, 62.5 mW, 0402 [1005 Metric], Thick Film, General Purpose"
			(at 0 0 0)
			(layer "B.Fab")
			(hide yes)
			(effects
				(font
					(size 1.27 1.27)
					(thickness 0.15)
				)
				(justify mirror)
			)
		)
		(property "MPN" "CR0402-FX-1002GLF"
			(at 0 0 0)
			(unlocked yes)
			(layer "B.Fab")
			(hide yes)
			(effects
				(font
					(size 1 1)
					(thickness 0.15)
				)
				(justify mirror)
			)
		)
		(property "Manufacturer" "Bourns"
			(at 0 0 0)
			(unlocked yes)
			(layer "B.Fab")
			(hide yes)
			(effects
				(font
					(size 1 1)
					(thickness 0.15)
				)
				(justify mirror)
			)
		)
		(property "License" "Apache-2.0"
			(at 0 0 0)
			(unlocked yes)
			(layer "B.Fab")
			(hide yes)
			(effects
				(font
					(size 1 1)
					(thickness 0.15)
				)
				(justify mirror)
			)
		)
		(property "Author" "Antmicro"
			(at 0 0 0)
			(unlocked yes)
			(layer "B.Fab")
			(hide yes)
			(effects
				(font
					(size 1 1)
					(thickness 0.15)
				)
				(justify mirror)
			)
		)
		(property "Val" "10k"
			(at 0 0 0)
			(unlocked yes)
			(layer "B.Fab")
			(hide yes)
			(effects
				(font
					(size 1 1)
					(thickness 0.15)
				)
				(justify mirror)
			)
		)
		(property "Tolerance" "1%"
			(at 0 0 0)
			(unlocked yes)
			(layer "B.Fab")
			(hide yes)
			(effects
				(font
					(size 1 1)
					(thickness 0.15)
				)
				(justify mirror)
			)
		)
		(sheetname "/Expansion connector/")
		(sheetfile "expansion_connector.kicad_sch")
		(attr smd)
		(fp_poly
			(pts
				(xy -0.925 0.47) (xy 0.925 0.47) (xy 0.925 -0.47) (xy -0.925 -0.47)
			)
			(stroke
				(width 0.05)
				(type default)
			)
			(fill no)
			(layer "B.CrtYd")
		)
		(fp_poly
			(pts
				(xy -0.5 0.25) (xy 0.5 0.25) (xy 0.5 -0.25) (xy -0.5 -0.25)
			)
			(stroke
				(width 0.15)
				(type solid)
			)
			(fill no)
			(layer "B.Fab")
		)
		(fp_text user "${REFERENCE}"
			(at -0.95 -3.168 0)
			(layer "B.Fab")
			(effects
				(font
					(size 0.7 0.7)
					(thickness 0.15)
				)
				(justify left bottom mirror)
			)
		)
		(fp_text user "License: Apache-2.0"
			(at -0.949999 -5.169 0)
			(layer "B.Fab")
			(effects
				(font
					(size 0.7 0.7)
					(thickness 0.15)
				)
				(justify left bottom mirror)
			)
		)
		(fp_text user "Author: Antmicro"
			(at -0.95 -4.169 0)
			(layer "B.Fab")
			(effects
				(font
					(size 0.7 0.7)
					(thickness 0.15)
				)
				(justify left bottom mirror)
			)
		)
		(pad "1" smd roundrect
			(at -0.48 0 180)
			(size 0.59 0.64)
			(layers "B.Cu" "B.Mask" "B.Paste")
			(roundrect_rratio 0.25)
			(net 341 "/Expansion connector/FMC_PRESENT")
			(pintype "passive")
		)
		(pad "2" smd roundrect
			(at 0.48 0 180)
			(size 0.59 0.64)
			(layers "B.Cu" "B.Mask" "B.Paste")
			(roundrect_rratio 0.25)
			(net 1 "GND")
			(pintype "passive")
		)
	)
	(footprint "antmicro-footprints:R_0402_1005Metric"
		(layer "B.Cu")
		(at 208.726 144)
		(descr "Resistor SMD 0402")
		(tags "resistor SMD 0402")
		(property "Reference" "R197"
			(at 0.95 -0.31 0)
			(layer "B.SilkS")
			(effects
				(font
					(size 0.7 0.7)
					(thickness 0.15)
				)
				(justify right top mirror)
			)
		)
		(property "Value" "R_1k_0402"
			(at -1.011843 -1.772047 0)
			(layer "B.Fab")
			(effects
				(font
					(size 0.7 0.7)
					(thickness 0.15)
				)
				(justify right top mirror)
			)
		)
		(property "Datasheet" "https://www.bourns.com/docs/product-datasheets/cr.pdf"
			(at 0 0 0)
			(layer "B.Fab")
			(hide yes)
			(effects
				(font
					(size 1.27 1.27)
					(thickness 0.15)
				)
				(justify mirror)
			)
		)
		(property "Description" "SMD Chip Resistor, 1 kohm, ± 1%, 63 mW, 0402 [1005 Metric], Thick Film, General Purpose"
			(at 0 0 0)
			(layer "B.Fab")
			(hide yes)
			(effects
				(font
					(size 1.27 1.27)
					(thickness 0.15)
				)
				(justify mirror)
			)
		)
		(property "MPN" "CR0402-FX-1001GLF"
			(at 0 0 180)
			(unlocked yes)
			(layer "B.Fab")
			(hide yes)
			(effects
				(font
					(size 1 1)
					(thickness 0.15)
				)
				(justify mirror)
			)
		)
		(property "Manufacturer" "Bourns"
			(at 0 0 180)
			(unlocked yes)
			(layer "B.Fab")
			(hide yes)
			(effects
				(font
					(size 1 1)
					(thickness 0.15)
				)
				(justify mirror)
			)
		)
		(property "License" "Apache-2.0"
			(at 0 0 180)
			(unlocked yes)
			(layer "B.Fab")
			(hide yes)
			(effects
				(font
					(size 1 1)
					(thickness 0.15)
				)
				(justify mirror)
			)
		)
		(property "Author" "Antmicro"
			(at 0 0 180)
			(unlocked yes)
			(layer "B.Fab")
			(hide yes)
			(effects
				(font
					(size 1 1)
					(thickness 0.15)
				)
				(justify mirror)
			)
		)
		(property "Val" "1k"
			(at 0 0 180)
			(unlocked yes)
			(layer "B.Fab")
			(hide yes)
			(effects
				(font
					(size 1 1)
					(thickness 0.15)
				)
				(justify mirror)
			)
		)
		(property "Tolerance" "1%"
			(at 0 0 180)
			(unlocked yes)
			(layer "B.Fab")
			(hide yes)
			(effects
				(font
					(size 1 1)
					(thickness 0.15)
				)
				(justify mirror)
			)
		)
		(sheetname "/SFP/")
		(sheetfile "sfp.kicad_sch")
		(attr smd)
		(fp_rect
			(start -0.925 0.47)
			(end 0.925 -0.47)
			(stroke
				(width 0.05)
				(type default)
			)
			(fill no)
			(layer "B.CrtYd")
		)
		(fp_rect
			(start -0.5 0.25)
			(end 0.5 -0.25)
			(stroke
				(width 0.15)
				(type solid)
			)
			(fill no)
			(layer "B.Fab")
		)
		(fp_text user "License: Apache-2.0"
			(at -0.95 -5.169 0)
			(layer "B.Fab")
			(effects
				(font
					(size 0.7 0.7)
					(thickness 0.15)
				)
				(justify right top mirror)
			)
		)
		(fp_text user "Author: Antmicro"
			(at -0.95 -4.169 0)
			(layer "B.Fab")
			(effects
				(font
					(size 0.7 0.7)
					(thickness 0.15)
				)
				(justify right top mirror)
			)
		)
		(fp_text user "${REFERENCE}"
			(at -0.95 -3.168 0)
			(layer "B.Fab")
			(effects
				(font
					(size 0.7 0.7)
					(thickness 0.15)
				)
				(justify right top mirror)
			)
		)
		(pad "1" smd roundrect
			(at -0.48 0)
			(size 0.59 0.64)
			(layers "B.Cu" "B.Mask" "B.Paste")
			(roundrect_rratio 0.25)
			(net 1296 "/SFP/SFP_MOD_ABS")
			(pintype "passive")
		)
		(pad "2" smd roundrect
			(at 0.48 0)
			(size 0.59 0.64)
			(layers "B.Cu" "B.Mask" "B.Paste")
			(roundrect_rratio 0.25)
			(net 11 "+1V8")
			(pintype "passive")
		)
	)
)
